# T6G (Grand Teton) — schematic netlist excerpt (pin names and nets, part order shuffled) for the footprints in the layout excerpt that follows; sources: Cadence DE-HDL packaged netlist, KiCad conversion of 04192023_DAF0TMB3IC0_F0TG_MB_C_brd_V02_OCP.brd

U59  74LVC2G07DW7  74LVC2G07DW-7 IC  pkg SOT363_0-65_2X1-25XC  page 140
  \1a\  = OCP_V3_2_PRSNT2_R_N
  GND  = GND
  \2a\  = OCP_V3_2_PRSNT3_R_N
  \2y\  = HP_LVC3_OCP_V3_2_PRSNT2_N_R
  VCC  = P3V3_AUX
  \1y\  = HP_LVC3_OCP_V3_2_PRSNT2_N_R

U241  74LVC2G08DP  EMPTY  pkg TSSOP8_0-65_3X3  page 143
  \1a\  = OCP_V3_2_PRSNT0_R_N
  \1b\  = OCP_V3_2_PRSNT1_R_N
  \2y\  = OCP_V3_2_PRSNT23_R_N
  GND  = GND
  \2a\  = OCP_V3_2_PRSNT2_R_N
  \2b\  = OCP_V3_2_PRSNT3_R_N
  \1y\  = OCP_V3_2_PRSNT01_R_N
  VCC  = P3V3_AUX

(kicad_pcb
	(version 20260206)
	(generator "pcbnew")
	(generator_version "10.0")
	(general
		(thickness 1.6)
		(legacy_teardrops no)
	)
	(paper "A4")
	(title_block
		(title "04192023_DAF0TMB3IC0_F0TG_MB_C_brd_V02_OCP.brd")
		(comment 1 "Grand Teton / footprints 3739-3740 of 8354")
	)
	(layers
		(0 "F.Cu" signal "TOP")
		(4 "In1.Cu" signal "GND")
		(6 "In2.Cu" signal "IN1")
		(8 "In3.Cu" signal "GND1")
		(10 "In4.Cu" signal "IN2")
		(12 "In5.Cu" signal "GND2")
		(14 "In6.Cu" signal "IN3")
		(16 "In7.Cu" signal "GND3")
		(18 "In8.Cu" signal "VCC")
		(20 "In9.Cu" signal "VCC1")
		(22 "In10.Cu" signal "GND4")
		(24 "In11.Cu" signal "IN4")
		(26 "In12.Cu" signal "GND5")
		(28 "In13.Cu" signal "IN5")
		(30 "In14.Cu" signal "GND6")
		(32 "In15.Cu" signal "IN6")
		(34 "In16.Cu" signal "GND7")
		(2 "B.Cu" signal "BOTTOM")
		(9 "F.Adhes" user "F.Adhesive")
		(11 "B.Adhes" user "B.Adhesive")
		(13 "F.Paste" user "Package Geometry/Pastemask Top")
		(15 "B.Paste" user "Package Geometry/Pastemask Bottom")
		(5 "F.SilkS" user "Ref Des/Silkscreen Top")
		(7 "B.SilkS" user "Ref Des/Silkscreen Bottom")
		(1 "F.Mask" user "Board Geometry/Soldermask Top")
		(3 "B.Mask" user "Board Geometry/Soldermask Bottom")
		(17 "Dwgs.User" user "User.Drawings")
		(19 "Cmts.User" user "User.Comments")
		(21 "Eco1.User" user "User.Eco1")
		(23 "Eco2.User" user "User.Eco2")
		(25 "Edge.Cuts" user "Board Geometry/Outline")
		(27 "Margin" user)
		(31 "F.CrtYd" user "Package Geometry/Place Bound Top")
		(29 "B.CrtYd" user "Package Geometry/Place Bound Bottom")
		(35 "F.Fab" user "Ref Des/Assembly Top")
		(33 "B.Fab" user "Ref Des/Assembly Bottom")
	)
	(footprint ""
		(layer "F.Cu")
		(at 5.35432 -74.719688)
		(property "Reference" "U241"
			(at -2.3876 -2.250948 0)
			(unlocked yes)
			(layer "F.SilkS")
			(effects
				(font
					(size 0.7874 0.5842)
					(thickness 0.1524)
				)
				(justify left)
			)
		)
		(property "Value" ""
			(at 0 0 0)
			(layer "F.Fab")
			(effects
				(font
					(size 1.27 1.27)
				)
			)
		)
		(duplicate_pad_numbers_are_jumpers no)
		(fp_line
			(start -1.207008 -1.549908)
			(end -1.207008 1.549908)
			(stroke
				(width 0.1524)
				(type default)
			)
			(layer "F.SilkS")
		)
		(fp_line
			(start -1.207008 1.549908)
			(end 1.207008 1.549908)
			(stroke
				(width 0.1524)
				(type default)
			)
			(layer "F.SilkS")
		)
		(fp_line
			(start -0.762508 -1.549908)
			(end -1.207008 -1.549908)
			(stroke
				(width 0.1524)
				(type default)
			)
			(layer "F.SilkS")
		)
		(fp_line
			(start 0 -0.635)
			(end -0.762508 -1.549908)
			(stroke
				(width 0.1524)
				(type default)
			)
			(layer "F.SilkS")
		)
		(fp_line
			(start 0.762508 -1.549908)
			(end 0 -0.635)
			(stroke
				(width 0.1524)
				(type default)
			)
			(layer "F.SilkS")
		)
		(fp_line
			(start 1.207008 -1.549908)
			(end 0.762508 -1.549908)
			(stroke
				(width 0.1524)
				(type default)
			)
			(layer "F.SilkS")
		)
		(fp_line
			(start 1.207008 1.549908)
			(end 1.207008 -1.549908)
			(stroke
				(width 0.1524)
				(type default)
			)
			(layer "F.SilkS")
		)
		(fp_poly
			(pts
				(xy -2.3876 -1.02489) (xy -3.4036 -0.51689) (xy -3.4036 -1.53289)
			)
			(stroke
				(width 0)
				(type default)
			)
			(fill yes)
			(layer "F.SilkS")
		)
		(fp_line
			(start -1.549908 -1.549908)
			(end -1.549908 1.549908)
			(stroke
				(width 0.1)
				(type default)
			)
			(layer "F.Fab")
		)
		(fp_line
			(start -1.549908 1.549908)
			(end 1.549908 1.549908)
			(stroke
				(width 0.1)
				(type default)
			)
			(layer "F.Fab")
		)
		(fp_line
			(start 1.549908 -1.549908)
			(end -1.549908 -1.549908)
			(stroke
				(width 0.1)
				(type default)
			)
			(layer "F.Fab")
		)
		(fp_line
			(start 1.549908 1.549908)
			(end 1.549908 -1.549908)
			(stroke
				(width 0.1)
				(type default)
			)
			(layer "F.Fab")
		)
		(fp_poly
			(pts
				(xy -3.4036 -1.53289) (xy -3.4036 -0.51689) (xy -2.3876 -1.02489)
			)
			(stroke
				(width 0)
				(type default)
			)
			(fill yes)
			(layer "F.Fab")
		)
		(pad "1" smd rect
			(at -1.774952 -1.02489 270)
			(size 0.508 0.8636)
			(layers "F.Cu" "F.Mask" "F.Paste")
			(net "OCP_V3_2_PRSNT0_R_N")
		)
		(pad "2" smd rect
			(at -1.774952 -0.32512 270)
			(size 0.4064 0.8636)
			(layers "F.Cu" "F.Mask" "F.Paste")
			(net "OCP_V3_2_PRSNT1_R_N")
		)
		(pad "3" smd rect
			(at -1.774952 0.32512 270)
			(size 0.4064 0.8636)
			(layers "F.Cu" "F.Mask" "F.Paste")
			(net "OCP_V3_2_PRSNT23_R_N")
		)
		(pad "4" smd rect
			(at -1.774952 1.02489 270)
			(size 0.508 0.8636)
			(layers "F.Cu" "F.Mask" "F.Paste")
			(net "GND")
		)
		(pad "5" smd rect
			(at 1.774952 1.02489 270)
			(size 0.508 0.8636)
			(layers "F.Cu" "F.Mask" "F.Paste")
			(net "OCP_V3_2_PRSNT2_R_N")
		)
		(pad "6" smd rect
			(at 1.774952 0.32512 270)
			(size 0.4064 0.8636)
			(layers "F.Cu" "F.Mask" "F.Paste")
			(net "OCP_V3_2_PRSNT3_R_N")
		)
		(pad "7" smd rect
			(at 1.774952 -0.32512 270)
			(size 0.4064 0.8636)
			(layers "F.Cu" "F.Mask" "F.Paste")
			(net "OCP_V3_2_PRSNT01_R_N")
		)
		(pad "8" smd rect
			(at 1.774952 -1.02489 270)
			(size 0.508 0.8636)
			(layers "F.Cu" "F.Mask" "F.Paste")
			(net "P3V3_AUX")
		)
	)
	(footprint ""
		(layer "F.Cu")
		(at 12.96416 -71.210678)
		(property "Reference" "U59"
			(at -1.2065 1.973072 0)
			(unlocked yes)
			(layer "F.SilkS")
			(effects
				(font
					(size 0.7874 0.5842)
					(thickness 0.1524)
				)
				(justify left)
			)
		)
		(property "Value" ""
			(at 0 0 0)
			(layer "F.Fab")
			(effects
				(font
					(size 1.27 1.27)
				)
			)
		)
		(duplicate_pad_numbers_are_jumpers no)
		(fp_line
			(start -1.38176 -1.100074)
			(end -1.38176 1.100074)
			(stroke
				(width 0.1524)
				(type default)
			)
			(layer "F.SilkS")
		)
		(fp_line
			(start -1.38176 1.100074)
			(end 1.38176 1.100074)
			(stroke
				(width 0.1524)
				(type default)
			)
			(layer "F.SilkS")
		)
		(fp_line
			(start -0.592074 -1.100074)
			(end -1.38176 -1.100074)
			(stroke
				(width 0.1524)
				(type default)
			)
			(layer "F.SilkS")
		)
		(fp_line
			(start 0 -0.508)
			(end -0.592074 -1.100074)
			(stroke
				(width 0.1524)
				(type default)
			)
			(layer "F.SilkS")
		)
		(fp_line
			(start 0.592074 -1.100074)
			(end 0 -0.508)
			(stroke
				(width 0.1524)
				(type default)
			)
			(layer "F.SilkS")
		)
		(fp_line
			(start 1.38176 -1.100074)
			(end 0.592074 -1.100074)
			(stroke
				(width 0.1524)
				(type default)
			)
			(layer "F.SilkS")
		)
		(fp_line
			(start 1.38176 1.100074)
			(end 1.38176 -1.100074)
			(stroke
				(width 0.1524)
				(type default)
			)
			(layer "F.SilkS")
		)
		(fp_poly
			(pts
				(xy -1.9431 -0.429768) (xy -1.9431 -0.870204) (xy -1.50241 -0.649986)
			)
			(stroke
				(width 0)
				(type default)
			)
			(fill yes)
			(layer "F.SilkS")
		)
		(fp_line
			(start -0.674878 -1.100074)
			(end -0.674878 1.100074)
			(stroke
				(width 0.1)
				(type default)
			)
			(layer "F.Fab")
		)
		(fp_line
			(start -0.674878 1.100074)
			(end 0.674878 1.100074)
			(stroke
				(width 0.1)
				(type default)
			)
			(layer "F.Fab")
		)
		(fp_line
			(start 0.674878 -1.100074)
			(end -0.674878 -1.100074)
			(stroke
				(width 0.1)
				(type default)
			)
			(layer "F.Fab")
		)
		(fp_line
			(start 0.674878 1.100074)
			(end 0.674878 -1.100074)
			(stroke
				(width 0.1)
				(type default)
			)
			(layer "F.Fab")
		)
		(fp_poly
			(pts
				(xy -1.9431 -0.870204) (xy -1.50241 -0.649986) (xy -1.9431 -0.429768)
			)
			(stroke
				(width 0)
				(type default)
			)
			(fill yes)
			(layer "F.Fab")
		)
		(pad "1" smd rect
			(at -0.94996 -0.649986 270)
			(size 0.4318 0.6096)
			(layers "F.Cu" "F.Mask" "F.Paste")
			(net "OCP_V3_2_PRSNT2_R_N")
		)
		(pad "2" smd rect
			(at -0.94996 0 270)
			(size 0.4318 0.6096)
			(layers "F.Cu" "F.Mask" "F.Paste")
			(net "GND")
		)
		(pad "3" smd rect
			(at -0.94996 0.649986 270)
			(size 0.4318 0.6096)
			(layers "F.Cu" "F.Mask" "F.Paste")
			(net "OCP_V3_2_PRSNT3_R_N")
		)
		(pad "4" smd rect
			(at 0.94996 0.649986 270)
			(size 0.4318 0.6096)
			(layers "F.Cu" "F.Mask" "F.Paste")
			(net "HP_LVC3_OCP_V3_2_PRSNT2_N_R")
		)
		(pad "5" smd rect
			(at 0.94996 0 270)
			(size 0.4318 0.6096)
			(layers "F.Cu" "F.Mask" "F.Paste")
			(net "P3V3_AUX")
		)
		(pad "6" smd rect
			(at 0.94996 -0.649986 270)
			(size 0.4318 0.6096)
			(layers "F.Cu" "F.Mask" "F.Paste")
			(net "HP_LVC3_OCP_V3_2_PRSNT2_N_R")
		)
	)
)
